# BASEBOARD_FAB2 (Tioga Pass) — schematic netlist excerpt (pin names and nets, part order shuffled) for the footprints in the layout excerpt that follows; sources: Cadence DE-HDL packaged netlist, KiCad conversion of Wiwynn_Tioga_Pass_MB.brd

CN8F2  CAP_A  0.01UF 25V 10% X7R  pkg 0402V  page 246 : A = P3V3_STBY ; B = GND
R1M13  RES  0.0 5% CHIP  pkg 0402  page 177 : A = LED_PCH_SSATA_HDD_N ; B = LED_SAS_ACT_R_N
C5G47  CAP_A  22.0UF 4V 20% X6S  pkg 0603V  page 242 : A = PVDDQ_ABC ; B = GND

(kicad_pcb
	(version 20260206)
	(generator "pcbnew")
	(generator_version "10.0")
	(general
		(thickness 1.6)
		(legacy_teardrops no)
	)
	(paper "A4")
	(title_block
		(title "Wiwynn_Tioga_Pass_MB.brd")
		(comment 1 "Tioga Pass / footprints 3417-3419 of 4770")
	)
	(layers
		(0 "F.Cu" signal "TOP")
		(4 "In1.Cu" signal "L2GND")
		(6 "In2.Cu" signal "L3")
		(8 "In3.Cu" signal "L4GND")
		(10 "In4.Cu" signal "L5")
		(12 "In5.Cu" signal "L6GND")
		(14 "In6.Cu" signal "L7VCC")
		(16 "In7.Cu" signal "L8VCC")
		(18 "In8.Cu" signal "L9GND")
		(20 "In9.Cu" signal "L10")
		(22 "In10.Cu" signal "L11GND")
		(24 "In11.Cu" signal "L12")
		(26 "In12.Cu" signal "L13GND")
		(2 "B.Cu" signal "BOTTOM")
		(9 "F.Adhes" user "F.Adhesive")
		(11 "B.Adhes" user "B.Adhesive")
		(13 "F.Paste" user "Package Geometry/Pastemask Top")
		(15 "B.Paste" user "Package Geometry/Pastemask Bottom")
		(5 "F.SilkS" user "Ref Des/Silkscreen Top")
		(7 "B.SilkS" user "Ref Des/Silkscreen Bottom")
		(1 "F.Mask" user "Board Geometry/Soldermask Top")
		(3 "B.Mask" user "Board Geometry/Soldermask Bottom")
		(17 "Dwgs.User" user "User.Drawings")
		(19 "Cmts.User" user "User.Comments")
		(21 "Eco1.User" user "User.Eco1")
		(23 "Eco2.User" user "User.Eco2")
		(25 "Edge.Cuts" user "Board Geometry/Outline")
		(27 "Margin" user)
		(31 "F.CrtYd" user "Package Geometry/Place Bound Top")
		(29 "B.CrtYd" user "Package Geometry/Place Bound Bottom")
		(35 "F.Fab" user "Ref Des/Assembly Top")
		(33 "B.Fab" user "Ref Des/Assembly Bottom")
	)
	(footprint ""
		(layer "B.Cu")
		(at 379.476 -19.304 90)
		(property "Reference" "CN8F2"
			(at 0.8382 -0.67818 90)
			(unlocked yes)
			(layer "B.SilkS")
			(effects
				(font
					(size 0.4064 0.254)
					(thickness 0.1524)
				)
				(justify left mirror)
			)
		)
		(property "Value" ""
			(at 0 0 90)
			(layer "B.Fab")
			(effects
				(font
					(size 1.27 1.27)
				)
				(justify mirror)
			)
		)
		(duplicate_pad_numbers_are_jumpers no)
		(fp_poly
			(pts
				(xy -0.3048 -0.1016) (xy -0.3048 0.9906) (xy 0.3048 0.9906) (xy 0.3048 -0.1016)
			)
			(stroke
				(width 0)
				(type default)
			)
			(fill no)
			(layer "B.CrtYd")
		)
		(fp_line
			(start 0.3048 -0.1016)
			(end 0.3048 0.9906)
			(stroke
				(width 0.1)
				(type default)
			)
			(layer "B.Fab")
		)
		(fp_line
			(start -0.3048 -0.1016)
			(end 0.3048 -0.1016)
			(stroke
				(width 0.1)
				(type default)
			)
			(layer "B.Fab")
		)
		(fp_line
			(start 0.3048 0.9906)
			(end -0.3048 0.9906)
			(stroke
				(width 0.1)
				(type default)
			)
			(layer "B.Fab")
		)
		(fp_line
			(start -0.3048 0.9906)
			(end -0.3048 -0.1016)
			(stroke
				(width 0.1)
				(type default)
			)
			(layer "B.Fab")
		)
		(pad "1" smd rect
			(at 0 0 270)
			(size 0.508 0.508)
			(layers "B.Cu" "B.Mask" "B.Paste")
			(net "P3V3_STBY")
		)
		(pad "2" smd rect
			(at 0 0.889 270)
			(size 0.508 0.508)
			(layers "B.Cu" "B.Mask" "B.Paste")
			(net "GND")
		)
		(zone
			(layer "B.Cu")
			(hatch none 0.5)
			(connect_pads
				(clearance 0)
			)
			(min_thickness 0.25)
			(keepout
				(tracks allowed)
				(vias not_allowed)
				(pads allowed)
				(copperpour not_allowed)
				(footprints allowed)
			)
			(placement
				(enabled no)
				(sheetname "")
			)
			(fill
				(thermal_gap 0.5)
				(thermal_bridge_width 0.5)
				(island_removal_mode 0)
			)
			(polygon
				(pts
					(xy 379.73 -19.558) (xy 379.73 -19.05) (xy 380.111 -19.05) (xy 380.111 -19.558)
				)
			)
		)
		(zone
			(layer "B.Cu")
			(hatch none 0.5)
			(connect_pads
				(clearance 0)
			)
			(min_thickness 0.25)
			(keepout
				(tracks not_allowed)
				(vias allowed)
				(pads allowed)
				(copperpour not_allowed)
				(footprints allowed)
			)
			(placement
				(enabled no)
				(sheetname "")
			)
			(fill
				(thermal_gap 0.5)
				(thermal_bridge_width 0.5)
				(island_removal_mode 0)
			)
			(polygon
				(pts
					(xy 380.111 -19.558) (xy 380.111 -19.05) (xy 379.73 -19.05) (xy 379.73 -19.558)
				)
			)
		)
	)
	(footprint ""
		(layer "B.Cu")
		(at 493.5474 -124.05868 180)
		(property "Reference" "R1M13"
			(at 0 0 0)
			(layer "B.SilkS")
			(hide yes)
			(effects
				(font
					(size 1.27 1.27)
				)
				(justify mirror)
			)
		)
		(property "Value" ""
			(at 0 0 0)
			(layer "B.Fab")
			(effects
				(font
					(size 1.27 1.27)
				)
				(justify mirror)
			)
		)
		(duplicate_pad_numbers_are_jumpers no)
		(fp_poly
			(pts
				(xy 0.2794 -0.1016) (xy -0.2794 -0.1016) (xy -0.2794 0.9906) (xy 0.2794 0.9906)
			)
			(stroke
				(width 0)
				(type default)
			)
			(fill no)
			(layer "B.CrtYd")
		)
		(fp_line
			(start 0.2794 0.9906)
			(end -0.2794 0.9906)
			(stroke
				(width 0.1)
				(type default)
			)
			(layer "B.Fab")
		)
		(fp_line
			(start 0.2794 -0.1016)
			(end 0.2794 0.9906)
			(stroke
				(width 0.1)
				(type default)
			)
			(layer "B.Fab")
		)
		(fp_line
			(start -0.2794 0.9906)
			(end -0.2794 -0.1016)
			(stroke
				(width 0.1)
				(type default)
			)
			(layer "B.Fab")
		)
		(fp_line
			(start -0.2794 -0.1016)
			(end 0.2794 -0.1016)
			(stroke
				(width 0.1)
				(type default)
			)
			(layer "B.Fab")
		)
		(pad "1" smd rect
			(at 0 0)
			(size 0.508 0.508)
			(layers "B.Cu" "B.Mask" "B.Paste")
			(net "LED_PCH_SSATA_HDD_N")
		)
		(pad "2" smd rect
			(at 0 0.889)
			(size 0.508 0.508)
			(layers "B.Cu" "B.Mask" "B.Paste")
			(net "LED_SAS_ACT_R_N")
		)
		(zone
			(layer "B.Cu")
			(hatch none 0.5)
			(connect_pads
				(clearance 0)
			)
			(min_thickness 0.25)
			(keepout
				(tracks not_allowed)
				(vias allowed)
				(pads allowed)
				(copperpour not_allowed)
				(footprints allowed)
			)
			(placement
				(enabled no)
				(sheetname "")
			)
			(fill
				(thermal_gap 0.5)
				(thermal_bridge_width 0.5)
				(island_removal_mode 0)
			)
			(polygon
				(pts
					(xy 493.2934 -124.69368) (xy 493.8014 -124.69368) (xy 493.8014 -124.31268) (xy 493.2934 -124.31268)
				)
			)
		)
		(zone
			(layer "B.Cu")
			(hatch none 0.5)
			(connect_pads
				(clearance 0)
			)
			(min_thickness 0.25)
			(keepout
				(tracks allowed)
				(vias not_allowed)
				(pads allowed)
				(copperpour not_allowed)
				(footprints allowed)
			)
			(placement
				(enabled no)
				(sheetname "")
			)
			(fill
				(thermal_gap 0.5)
				(thermal_bridge_width 0.5)
				(island_removal_mode 0)
			)
			(polygon
				(pts
					(xy 493.2934 -124.31268) (xy 493.8014 -124.31268) (xy 493.8014 -124.69368) (xy 493.2934 -124.69368)
				)
			)
		)
	)
	(footprint ""
		(layer "B.Cu")
		(at 269.559532 -12.954 90)
		(property "Reference" "C5G47"
			(at -1.14681 0.76708 180)
			(unlocked yes)
			(layer "B.SilkS")
			(effects
				(font
					(size 0.7874 0.5842)
					(thickness 0.1524)
				)
				(justify mirror)
			)
		)
		(property "Value" ""
			(at 0 0 90)
			(layer "B.Fab")
			(effects
				(font
					(size 1.27 1.27)
				)
				(justify mirror)
			)
		)
		(duplicate_pad_numbers_are_jumpers no)
		(fp_rect
			(start -0.4953 -0.2032)
			(end 0.4953 1.6002)
			(stroke
				(width 0)
				(type default)
			)
			(fill no)
			(layer "B.CrtYd")
		)
		(fp_line
			(start 0.4953 -0.2032)
			(end -0.4953 -0.2032)
			(stroke
				(width 0.1)
				(type default)
			)
			(layer "B.Fab")
		)
		(fp_line
			(start -0.4953 -0.2032)
			(end -0.4953 1.6002)
			(stroke
				(width 0.1)
				(type default)
			)
			(layer "B.Fab")
		)
		(fp_line
			(start 0.4953 1.6002)
			(end 0.4953 -0.2032)
			(stroke
				(width 0.1)
				(type default)
			)
			(layer "B.Fab")
		)
		(fp_line
			(start -0.4953 1.6002)
			(end 0.4953 1.6002)
			(stroke
				(width 0.1)
				(type default)
			)
			(layer "B.Fab")
		)
		(pad "1" smd rect
			(at 0 0 270)
			(size 0.762 0.889)
			(layers "B.Cu" "B.Mask" "B.Paste")
			(net "PVDDQ_ABC")
		)
		(pad "2" smd rect
			(at 0 1.397 270)
			(size 0.762 0.889)
			(layers "B.Cu" "B.Mask" "B.Paste")
			(net "GND")
		)
		(zone
			(layer "B.Cu")
			(hatch none 0.5)
			(connect_pads
				(clearance 0)
			)
			(min_thickness 0.25)
			(keepout
				(tracks not_allowed)
				(vias allowed)
				(pads allowed)
				(copperpour not_allowed)
				(footprints allowed)
			)
			(placement
				(enabled no)
				(sheetname "")
			)
			(fill
				(thermal_gap 0.5)
				(thermal_bridge_width 0.5)
				(island_removal_mode 0)
			)
			(polygon
				(pts
					(xy 270.004032 -12.573) (xy 270.512032 -12.573) (xy 270.512032 -13.335) (xy 270.004032 -13.335)
				)
			)
		)
	)
)
